(kicad_pcb
	(version 20260206)
	(generator "pcbnew")
	(generator_version "10.0")
	(general
		(thickness 1.6)
		(legacy_teardrops no)
	)
	(paper "A4")
	(title_block
		(title "v2-pdb — ms_pdb_v2.brd")
		(comment 1 "Open CloudServer (Microsoft) / footprints 111-116 of 348")
	)
	(layers
		(0 "F.Cu" signal "TOP")
		(4 "In1.Cu" signal "GND")
		(6 "In2.Cu" signal "IN1")
		(8 "In3.Cu" signal "VCC")
		(10 "In4.Cu" signal "VCC1")
		(12 "In5.Cu" signal "IN2")
		(14 "In6.Cu" signal "GND1")
		(2 "B.Cu" signal "BOTTOM")
		(9 "F.Adhes" user "F.Adhesive")
		(11 "B.Adhes" user "B.Adhesive")
		(13 "F.Paste" user "Package Geometry/Pastemask Top")
		(15 "B.Paste" user "Package Geometry/Pastemask Bottom")
		(5 "F.SilkS" user "Ref Des/Silkscreen Top")
		(7 "B.SilkS" user "Ref Des/Silkscreen Bottom")
		(1 "F.Mask" user "Board Geometry/Soldermask Top")
		(3 "B.Mask" user "Board Geometry/Soldermask Bottom")
		(17 "Dwgs.User" user "User.Drawings")
		(19 "Cmts.User" user "User.Comments")
		(21 "Eco1.User" user "User.Eco1")
		(23 "Eco2.User" user "User.Eco2")
		(25 "Edge.Cuts" user "Board Geometry/Outline")
		(27 "Margin" user)
		(31 "F.CrtYd" user "Package Geometry/Place Bound Top")
		(29 "B.CrtYd" user "Package Geometry/Place Bound Bottom")
		(35 "F.Fab" user "Ref Des/Assembly Top")
		(33 "B.Fab" user "Ref Des/Assembly Bottom")
	)
	(footprint ""
		(layer "F.Cu")
		(at 51.411124 -262.266176 180)
		(property "Reference" "CE7"
			(at -3.278124 3.86588 0)
			(unlocked yes)
			(layer "F.SilkS")
			(effects
				(font
					(size 0.7874 0.5842)
					(thickness 0.1524)
				)
				(justify left)
			)
		)
		(property "Value" ""
			(at 0 0 180)
			(layer "F.Fab")
			(effects
				(font
					(size 1.27 1.27)
				)
			)
		)
		(duplicate_pad_numbers_are_jumpers no)
		(fp_line
			(start 0 -4.2672)
			(end 0 4.2672)
			(stroke
				(width 0.1524)
				(type default)
			)
			(layer "F.SilkS")
		)
		(fp_circle
			(center 0 0)
			(end -4.2672 0)
			(stroke
				(width 0.1524)
				(type default)
			)
			(fill no)
			(layer "F.SilkS")
		)
		(fp_poly
			(pts
				(arc
					(start 0 -4.2672)
					(mid 4.2672 0)
					(end 0 4.2672)
				)
			)
			(stroke
				(width 0)
				(type default)
			)
			(fill yes)
			(layer "F.SilkS")
		)
		(fp_poly
			(pts
				(xy -2.5146 -0.762) (xy -0.9906 -0.762) (xy -0.9906 0.762) (xy -2.5146 0.762)
			)
			(stroke
				(width 0)
				(type default)
			)
			(fill no)
			(layer "B.CrtYd")
		)
		(fp_poly
			(pts
				(arc
					(start 1.7526 0.762)
					(mid 2.291415 -0.538815)
					(end 0.9906 0)
				)
				(arc
					(start 0.9906 0.0254)
					(mid 1.206345 0.546255)
					(end 1.7272 0.762)
				)
			)
			(stroke
				(width 0)
				(type default)
			)
			(fill no)
			(layer "B.CrtYd")
		)
		(fp_poly
			(pts
				(arc
					(start -4.2672 0)
					(mid 4.2672 0)
					(end -4.2672 0)
				)
			)
			(stroke
				(width 0)
				(type default)
			)
			(fill no)
			(layer "F.CrtYd")
		)
		(fp_circle
			(center 0 0)
			(end -4.2672 0)
			(stroke
				(width 0.1)
				(type default)
			)
			(fill no)
			(layer "F.Fab")
		)
		(fp_text user "+"
			(at -6.549898 -0.069596 180)
			(unlocked yes)
			(layer "F.SilkS")
			(effects
				(font
					(size 1.905 1.4224)
					(thickness 0.1524)
				)
				(justify left)
			)
		)
		(fp_text user "+"
			(at -5.6642 -0.34925 180)
			(unlocked yes)
			(layer "F.Fab")
			(effects
				(font
					(size 1.905 1.4224)
					(thickness 0.000001)
				)
				(justify left)
			)
		)
		(pad "1" thru_hole rect
			(at -1.75006 0 180)
			(size 1.397 1.397)
			(drill 0.9144)
			(layers "*.Cu" "*.Mask")
			(remove_unused_layers no)
			(net "P12V")
			(clearance 0.0127)
			(thermal_gap 0.0127)
			(padstack
				(mode front_inner_back)
				(layer "Inner"
					(shape circle)
					(size 1.397 1.397)
					(clearance 0.0127)
				)
				(layer "B.Cu"
					(shape rect)
					(size 1.397 1.397)
					(clearance 0.0127)
				)
			)
		)
		(pad "2" thru_hole circle
			(at 1.75006 0 180)
			(size 1.397 1.397)
			(drill 0.9144)
			(layers "*.Cu" "*.Mask")
			(remove_unused_layers no)
			(net "GND")
			(clearance 0.0127)
			(thermal_gap 0.0127)
		)
	)
	(footprint ""
		(layer "F.Cu")
		(at 69.108828 -304.009806 90)
		(property "Reference" "C54"
			(at 1.035812 0.169926 90)
			(unlocked yes)
			(layer "F.SilkS")
			(effects
				(font
					(size 0.7874 0.5842)
					(thickness 0.1524)
				)
				(justify left)
			)
		)
		(property "Value" ""
			(at 0 0 90)
			(layer "F.Fab")
			(effects
				(font
					(size 1.27 1.27)
				)
			)
		)
		(duplicate_pad_numbers_are_jumpers no)
		(fp_line
			(start 0.7874 -0.4064)
			(end 0.7874 0.4064)
			(stroke
				(width 0.1524)
				(type default)
			)
			(layer "F.SilkS")
		)
		(fp_line
			(start -0.7874 -0.4064)
			(end 0.7874 -0.4064)
			(stroke
				(width 0.1524)
				(type default)
			)
			(layer "F.SilkS")
		)
		(fp_line
			(start 0 0.381)
			(end 0 -0.381)
			(stroke
				(width 0.1524)
				(type default)
			)
			(layer "F.SilkS")
		)
		(fp_line
			(start 0.7874 0.4064)
			(end -0.7874 0.4064)
			(stroke
				(width 0.1524)
				(type default)
			)
			(layer "F.SilkS")
		)
		(fp_line
			(start -0.7874 0.4064)
			(end -0.7874 -0.4064)
			(stroke
				(width 0.1524)
				(type default)
			)
			(layer "F.SilkS")
		)
		(fp_poly
			(pts
				(xy -0.5334 0.254) (xy -0.635 0.254) (xy -0.635 0.2286) (xy -0.635 -0.254) (xy -0.5334 -0.254) (xy -0.5334 -0.2794)
				(xy 0.5334 -0.2794) (xy 0.5334 -0.254) (xy 0.635 -0.254) (xy 0.635 0.254) (xy 0.5334 0.254) (xy 0.5334 0.2794)
				(xy -0.508 0.2794) (xy -0.5334 0.2794)
			)
			(stroke
				(width 0)
				(type default)
			)
			(fill no)
			(layer "F.CrtYd")
		)
		(pad "1" smd rect
			(at 0.40005 0 90)
			(size 0.4572 0.508)
			(layers "F.Cu" "F.Mask" "F.Paste")
			(net "P12V")
		)
		(pad "2" smd rect
			(at -0.40005 0 90)
			(size 0.4572 0.508)
			(layers "F.Cu" "F.Mask" "F.Paste")
			(net "GND")
		)
	)
	(footprint ""
		(layer "F.Cu")
		(at 72.19696 -350.498918 90)
		(property "Reference" "C60"
			(at 1.140206 0.322072 90)
			(unlocked yes)
			(layer "F.SilkS")
			(effects
				(font
					(size 0.7874 0.5842)
					(thickness 0.1524)
				)
				(justify left)
			)
		)
		(property "Value" ""
			(at 0 0 90)
			(layer "F.Fab")
			(effects
				(font
					(size 1.27 1.27)
				)
			)
		)
		(duplicate_pad_numbers_are_jumpers no)
		(fp_line
			(start 0.7874 -0.4064)
			(end 0.7874 0.4064)
			(stroke
				(width 0.1524)
				(type default)
			)
			(layer "F.SilkS")
		)
		(fp_line
			(start -0.7874 -0.4064)
			(end 0.7874 -0.4064)
			(stroke
				(width 0.1524)
				(type default)
			)
			(layer "F.SilkS")
		)
		(fp_line
			(start 0 0.381)
			(end 0 -0.381)
			(stroke
				(width 0.1524)
				(type default)
			)
			(layer "F.SilkS")
		)
		(fp_line
			(start 0.7874 0.4064)
			(end -0.7874 0.4064)
			(stroke
				(width 0.1524)
				(type default)
			)
			(layer "F.SilkS")
		)
		(fp_line
			(start -0.7874 0.4064)
			(end -0.7874 -0.4064)
			(stroke
				(width 0.1524)
				(type default)
			)
			(layer "F.SilkS")
		)
		(fp_poly
			(pts
				(xy -0.5334 0.254) (xy -0.635 0.254) (xy -0.635 0.2286) (xy -0.635 -0.254) (xy -0.5334 -0.254) (xy -0.5334 -0.2794)
				(xy 0.5334 -0.2794) (xy 0.5334 -0.254) (xy 0.635 -0.254) (xy 0.635 0.254) (xy 0.5334 0.254) (xy 0.5334 0.2794)
				(xy -0.508 0.2794) (xy -0.5334 0.2794)
			)
			(stroke
				(width 0)
				(type default)
			)
			(fill no)
			(layer "F.CrtYd")
		)
		(pad "1" smd rect
			(at 0.40005 0 90)
			(size 0.4572 0.508)
			(layers "F.Cu" "F.Mask" "F.Paste")
			(net "P12V")
		)
		(pad "2" smd rect
			(at -0.40005 0 90)
			(size 0.4572 0.508)
			(layers "F.Cu" "F.Mask" "F.Paste")
			(net "GND")
		)
	)
	(footprint ""
		(layer "F.Cu")
		(at 69.41947 -216.615772 90)
		(property "Reference" "C40"
			(at 1.187196 -0.020574 90)
			(unlocked yes)
			(layer "F.SilkS")
			(effects
				(font
					(size 0.7874 0.5842)
					(thickness 0.1524)
				)
				(justify left)
			)
		)
		(property "Value" ""
			(at 0 0 90)
			(layer "F.Fab")
			(effects
				(font
					(size 1.27 1.27)
				)
			)
		)
		(duplicate_pad_numbers_are_jumpers no)
		(fp_line
			(start 0.7874 -0.4064)
			(end 0.7874 0.4064)
			(stroke
				(width 0.1524)
				(type default)
			)
			(layer "F.SilkS")
		)
		(fp_line
			(start -0.7874 -0.4064)
			(end 0.7874 -0.4064)
			(stroke
				(width 0.1524)
				(type default)
			)
			(layer "F.SilkS")
		)
		(fp_line
			(start 0 0.381)
			(end 0 -0.381)
			(stroke
				(width 0.1524)
				(type default)
			)
			(layer "F.SilkS")
		)
		(fp_line
			(start 0.7874 0.4064)
			(end -0.7874 0.4064)
			(stroke
				(width 0.1524)
				(type default)
			)
			(layer "F.SilkS")
		)
		(fp_line
			(start -0.7874 0.4064)
			(end -0.7874 -0.4064)
			(stroke
				(width 0.1524)
				(type default)
			)
			(layer "F.SilkS")
		)
		(fp_poly
			(pts
				(xy -0.5334 0.254) (xy -0.635 0.254) (xy -0.635 0.2286) (xy -0.635 -0.254) (xy -0.5334 -0.254) (xy -0.5334 -0.2794)
				(xy 0.5334 -0.2794) (xy 0.5334 -0.254) (xy 0.635 -0.254) (xy 0.635 0.254) (xy 0.5334 0.254) (xy 0.5334 0.2794)
				(xy -0.508 0.2794) (xy -0.5334 0.2794)
			)
			(stroke
				(width 0)
				(type default)
			)
			(fill no)
			(layer "F.CrtYd")
		)
		(pad "1" smd rect
			(at 0.40005 0 90)
			(size 0.4572 0.508)
			(layers "F.Cu" "F.Mask" "F.Paste")
			(net "P12V")
		)
		(pad "2" smd rect
			(at -0.40005 0 90)
			(size 0.4572 0.508)
			(layers "F.Cu" "F.Mask" "F.Paste")
			(net "GND")
		)
	)
	(footprint ""
		(layer "F.Cu")
		(at 73.532746 -439.03646 90)
		(property "Reference" "C74"
			(at 1.327912 0.190754 90)
			(unlocked yes)
			(layer "F.SilkS")
			(effects
				(font
					(size 0.7874 0.5842)
					(thickness 0.1524)
				)
				(justify left)
			)
		)
		(property "Value" ""
			(at 0 0 90)
			(layer "F.Fab")
			(effects
				(font
					(size 1.27 1.27)
				)
			)
		)
		(duplicate_pad_numbers_are_jumpers no)
		(fp_line
			(start 0.7874 -0.4064)
			(end 0.7874 0.4064)
			(stroke
				(width 0.1524)
				(type default)
			)
			(layer "F.SilkS")
		)
		(fp_line
			(start -0.7874 -0.4064)
			(end 0.7874 -0.4064)
			(stroke
				(width 0.1524)
				(type default)
			)
			(layer "F.SilkS")
		)
		(fp_line
			(start 0 0.381)
			(end 0 -0.381)
			(stroke
				(width 0.1524)
				(type default)
			)
			(layer "F.SilkS")
		)
		(fp_line
			(start 0.7874 0.4064)
			(end -0.7874 0.4064)
			(stroke
				(width 0.1524)
				(type default)
			)
			(layer "F.SilkS")
		)
		(fp_line
			(start -0.7874 0.4064)
			(end -0.7874 -0.4064)
			(stroke
				(width 0.1524)
				(type default)
			)
			(layer "F.SilkS")
		)
		(fp_poly
			(pts
				(xy -0.5334 0.254) (xy -0.635 0.254) (xy -0.635 0.2286) (xy -0.635 -0.254) (xy -0.5334 -0.254) (xy -0.5334 -0.2794)
				(xy 0.5334 -0.2794) (xy 0.5334 -0.254) (xy 0.635 -0.254) (xy 0.635 0.254) (xy 0.5334 0.254) (xy 0.5334 0.2794)
				(xy -0.508 0.2794) (xy -0.5334 0.2794)
			)
			(stroke
				(width 0)
				(type default)
			)
			(fill no)
			(layer "F.CrtYd")
		)
		(pad "1" smd rect
			(at 0.40005 0 90)
			(size 0.4572 0.508)
			(layers "F.Cu" "F.Mask" "F.Paste")
			(net "P12V")
		)
		(pad "2" smd rect
			(at -0.40005 0 90)
			(size 0.4572 0.508)
			(layers "F.Cu" "F.Mask" "F.Paste")
			(net "GND")
		)
	)
	(footprint ""
		(layer "F.Cu")
		(at 71.423022 -63.973456 -90)
		(property "Reference" "C10"
			(at -2.559304 0.082804 90)
			(unlocked yes)
			(layer "F.SilkS")
			(effects
				(font
					(size 0.7874 0.5842)
					(thickness 0.1524)
				)
				(justify left)
			)
		)
		(property "Value" ""
			(at 0 0 270)
			(layer "F.Fab")
			(effects
				(font
					(size 1.27 1.27)
				)
			)
		)
		(duplicate_pad_numbers_are_jumpers no)
		(fp_line
			(start -0.7874 0.4064)
			(end -0.7874 -0.4064)
			(stroke
				(width 0.1524)
				(type default)
			)
			(layer "F.SilkS")
		)
		(fp_line
			(start 0.7874 0.4064)
			(end -0.7874 0.4064)
			(stroke
				(width 0.1524)
				(type default)
			)
			(layer "F.SilkS")
		)
		(fp_line
			(start 0 0.381)
			(end 0 -0.381)
			(stroke
				(width 0.1524)
				(type default)
			)
			(layer "F.SilkS")
		)
		(fp_line
			(start -0.7874 -0.4064)
			(end 0.7874 -0.4064)
			(stroke
				(width 0.1524)
				(type default)
			)
			(layer "F.SilkS")
		)
		(fp_line
			(start 0.7874 -0.4064)
			(end 0.7874 0.4064)
			(stroke
				(width 0.1524)
				(type default)
			)
			(layer "F.SilkS")
		)
		(fp_poly
			(pts
				(xy -0.5334 0.254) (xy -0.635 0.254) (xy -0.635 0.2286) (xy -0.635 -0.254) (xy -0.5334 -0.254) (xy -0.5334 -0.2794)
				(xy 0.5334 -0.2794) (xy 0.5334 -0.254) (xy 0.635 -0.254) (xy 0.635 0.254) (xy 0.5334 0.254) (xy 0.5334 0.2794)
				(xy -0.508 0.2794) (xy -0.5334 0.2794)
			)
			(stroke
				(width 0)
				(type default)
			)
			(fill no)
			(layer "F.CrtYd")
		)
		(pad "1" smd rect
			(at 0.40005 0 270)
			(size 0.4572 0.508)
			(layers "F.Cu" "F.Mask" "F.Paste")
			(net "P12V")
		)
		(pad "2" smd rect
			(at -0.40005 0 270)
			(size 0.4572 0.508)
			(layers "F.Cu" "F.Mask" "F.Paste")
			(net "GND")
		)
	)
)
